(kicad_pcb
	(version 20260206)
	(generator "pcbnew")
	(generator_version "10.0")
	(general
		(thickness 1.6)
		(legacy_teardrops no)
	)
	(paper "A4")
	(title_block
		(title "12092022_DA0F0TMDCD0_F0T_Management_Board_D_brd_V3_OCP.brd")
		(comment 1 "Grand Teton / footprints 74-79 of 1440")
	)
	(layers
		(0 "F.Cu" signal "TOP")
		(4 "In1.Cu" signal "GND")
		(6 "In2.Cu" signal "IN1")
		(8 "In3.Cu" signal "GND1")
		(10 "In4.Cu" signal "IN2")
		(12 "In5.Cu" signal "VCC")
		(14 "In6.Cu" signal "VCC1")
		(16 "In7.Cu" signal "IN3")
		(18 "In8.Cu" signal "GND2")
		(20 "In9.Cu" signal "IN4")
		(22 "In10.Cu" signal "GND3")
		(2 "B.Cu" signal "BOTTOM")
		(9 "F.Adhes" user "F.Adhesive")
		(11 "B.Adhes" user "B.Adhesive")
		(13 "F.Paste" user "Package Geometry/Pastemask Top")
		(15 "B.Paste" user "Package Geometry/Pastemask Bottom")
		(5 "F.SilkS" user "Ref Des/Silkscreen Top")
		(7 "B.SilkS" user "Ref Des/Silkscreen Bottom")
		(1 "F.Mask" user "Board Geometry/Soldermask Top")
		(3 "B.Mask" user "Board Geometry/Soldermask Bottom")
		(17 "Dwgs.User" user "User.Drawings")
		(19 "Cmts.User" user "User.Comments")
		(21 "Eco1.User" user "User.Eco1")
		(23 "Eco2.User" user "User.Eco2")
		(25 "Edge.Cuts" user "Board Geometry/Outline")
		(27 "Margin" user)
		(31 "F.CrtYd" user "Package Geometry/Place Bound Top")
		(29 "B.CrtYd" user "Package Geometry/Place Bound Bottom")
		(35 "F.Fab" user "Ref Des/Assembly Top")
		(33 "B.Fab" user "Ref Des/Assembly Bottom")
	)
	(footprint ""
		(layer "F.Cu")
		(at 85.29955 -46.717204 180)
		(property "Reference" "R347"
			(at 0 0 180)
			(layer "F.SilkS")
			(hide yes)
			(effects
				(font
					(size 1.27 1.27)
				)
			)
		)
		(property "Value" ""
			(at 0 0 180)
			(layer "F.Fab")
			(effects
				(font
					(size 1.27 1.27)
				)
			)
		)
		(duplicate_pad_numbers_are_jumpers no)
		(fp_line
			(start 0.7874 0.4064)
			(end -0.7874 0.4064)
			(stroke
				(width 0.1524)
				(type default)
			)
			(layer "F.SilkS")
		)
		(fp_line
			(start 0.7874 -0.4064)
			(end 0.7874 0.4064)
			(stroke
				(width 0.1524)
				(type default)
			)
			(layer "F.SilkS")
		)
		(fp_line
			(start -0.7874 0.4064)
			(end -0.7874 -0.4064)
			(stroke
				(width 0.1524)
				(type default)
			)
			(layer "F.SilkS")
		)
		(fp_line
			(start -0.7874 -0.4064)
			(end 0.7874 -0.4064)
			(stroke
				(width 0.1524)
				(type default)
			)
			(layer "F.SilkS")
		)
		(fp_line
			(start 0.67945 0.3048)
			(end 0.120396 0.3048)
			(stroke
				(width 0.1)
				(type default)
			)
			(layer "F.Fab")
		)
		(fp_line
			(start 0.67945 -0.3048)
			(end 0.67945 0.3048)
			(stroke
				(width 0.1)
				(type default)
			)
			(layer "F.Fab")
		)
		(fp_line
			(start 0.12065 -0.2794)
			(end 0.12065 -0.3048)
			(stroke
				(width 0.1)
				(type default)
			)
			(layer "F.Fab")
		)
		(fp_line
			(start 0.12065 -0.3048)
			(end 0.67945 -0.3048)
			(stroke
				(width 0.1)
				(type default)
			)
			(layer "F.Fab")
		)
		(fp_line
			(start 0.120396 0.3048)
			(end 0.120396 0.2794)
			(stroke
				(width 0.1)
				(type default)
			)
			(layer "F.Fab")
		)
		(fp_line
			(start 0.120396 0.2794)
			(end -0.12065 0.2794)
			(stroke
				(width 0.1)
				(type default)
			)
			(layer "F.Fab")
		)
		(fp_line
			(start -0.12065 0.3048)
			(end -0.67945 0.3048)
			(stroke
				(width 0.1)
				(type default)
			)
			(layer "F.Fab")
		)
		(fp_line
			(start -0.12065 0.2794)
			(end -0.12065 0.3048)
			(stroke
				(width 0.1)
				(type default)
			)
			(layer "F.Fab")
		)
		(fp_line
			(start -0.12065 -0.2794)
			(end 0.12065 -0.2794)
			(stroke
				(width 0.1)
				(type default)
			)
			(layer "F.Fab")
		)
		(fp_line
			(start -0.12065 -0.305054)
			(end -0.12065 -0.2794)
			(stroke
				(width 0.1)
				(type default)
			)
			(layer "F.Fab")
		)
		(fp_line
			(start -0.67945 0.3048)
			(end -0.67945 -0.305054)
			(stroke
				(width 0.1)
				(type default)
			)
			(layer "F.Fab")
		)
		(fp_line
			(start -0.67945 -0.305054)
			(end -0.12065 -0.305054)
			(stroke
				(width 0.1)
				(type default)
			)
			(layer "F.Fab")
		)
		(pad "1" smd circle
			(at -0.40005 0 180)
			(size 0 0)
			(layers "F.Cu" "F.Mask" "F.Paste")
			(net "GND")
		)
		(pad "2" smd circle
			(at 0.40005 0 180)
			(size 0 0)
			(layers "F.Cu" "F.Mask" "F.Paste")
			(net "M_BMC_DDR4_MBA1")
		)
	)
	(footprint ""
		(layer "F.Cu")
		(at 37.61232 -106.4895 180)
		(property "Reference" "R482"
			(at 0 0 180)
			(layer "F.SilkS")
			(hide yes)
			(effects
				(font
					(size 1.27 1.27)
				)
			)
		)
		(property "Value" ""
			(at 0 0 180)
			(layer "F.Fab")
			(effects
				(font
					(size 1.27 1.27)
				)
			)
		)
		(duplicate_pad_numbers_are_jumpers no)
		(fp_line
			(start 0.7874 0.4064)
			(end -0.7874 0.4064)
			(stroke
				(width 0.1524)
				(type default)
			)
			(layer "F.SilkS")
		)
		(fp_line
			(start 0.7874 -0.4064)
			(end 0.7874 0.4064)
			(stroke
				(width 0.1524)
				(type default)
			)
			(layer "F.SilkS")
		)
		(fp_line
			(start -0.7874 0.4064)
			(end -0.7874 -0.4064)
			(stroke
				(width 0.1524)
				(type default)
			)
			(layer "F.SilkS")
		)
		(fp_line
			(start -0.7874 -0.4064)
			(end 0.7874 -0.4064)
			(stroke
				(width 0.1524)
				(type default)
			)
			(layer "F.SilkS")
		)
		(fp_line
			(start 0.67945 0.3048)
			(end 0.120396 0.3048)
			(stroke
				(width 0.1)
				(type default)
			)
			(layer "F.Fab")
		)
		(fp_line
			(start 0.67945 -0.3048)
			(end 0.67945 0.3048)
			(stroke
				(width 0.1)
				(type default)
			)
			(layer "F.Fab")
		)
		(fp_line
			(start 0.12065 -0.2794)
			(end 0.12065 -0.3048)
			(stroke
				(width 0.1)
				(type default)
			)
			(layer "F.Fab")
		)
		(fp_line
			(start 0.12065 -0.3048)
			(end 0.67945 -0.3048)
			(stroke
				(width 0.1)
				(type default)
			)
			(layer "F.Fab")
		)
		(fp_line
			(start 0.120396 0.3048)
			(end 0.120396 0.2794)
			(stroke
				(width 0.1)
				(type default)
			)
			(layer "F.Fab")
		)
		(fp_line
			(start 0.120396 0.2794)
			(end -0.12065 0.2794)
			(stroke
				(width 0.1)
				(type default)
			)
			(layer "F.Fab")
		)
		(fp_line
			(start -0.12065 0.3048)
			(end -0.67945 0.3048)
			(stroke
				(width 0.1)
				(type default)
			)
			(layer "F.Fab")
		)
		(fp_line
			(start -0.12065 0.2794)
			(end -0.12065 0.3048)
			(stroke
				(width 0.1)
				(type default)
			)
			(layer "F.Fab")
		)
		(fp_line
			(start -0.12065 -0.2794)
			(end 0.12065 -0.2794)
			(stroke
				(width 0.1)
				(type default)
			)
			(layer "F.Fab")
		)
		(fp_line
			(start -0.12065 -0.305054)
			(end -0.12065 -0.2794)
			(stroke
				(width 0.1)
				(type default)
			)
			(layer "F.Fab")
		)
		(fp_line
			(start -0.67945 0.3048)
			(end -0.67945 -0.305054)
			(stroke
				(width 0.1)
				(type default)
			)
			(layer "F.Fab")
		)
		(fp_line
			(start -0.67945 -0.305054)
			(end -0.12065 -0.305054)
			(stroke
				(width 0.1)
				(type default)
			)
			(layer "F.Fab")
		)
		(pad "1" smd circle
			(at -0.40005 0 180)
			(size 0 0)
			(layers "F.Cu" "F.Mask" "F.Paste")
			(net "SPI_PCH_MUXED_IO0")
		)
		(pad "2" smd circle
			(at 0.40005 0 180)
			(size 0 0)
			(layers "F.Cu" "F.Mask" "F.Paste")
			(net "SPI_PCH_IO0_FLASH_R1")
		)
	)
	(footprint ""
		(layer "F.Cu")
		(at 16.002 -102.743 -90)
		(property "Reference" "R574"
			(at 0 0 270)
			(layer "F.SilkS")
			(hide yes)
			(effects
				(font
					(size 1.27 1.27)
				)
			)
		)
		(property "Value" ""
			(at 0 0 270)
			(layer "F.Fab")
			(effects
				(font
					(size 1.27 1.27)
				)
			)
		)
		(duplicate_pad_numbers_are_jumpers no)
		(fp_line
			(start -0.7874 0.4064)
			(end -0.7874 -0.4064)
			(stroke
				(width 0.1524)
				(type default)
			)
			(layer "F.SilkS")
		)
		(fp_line
			(start 0.7874 0.4064)
			(end -0.7874 0.4064)
			(stroke
				(width 0.1524)
				(type default)
			)
			(layer "F.SilkS")
		)
		(fp_line
			(start -0.7874 -0.4064)
			(end 0.7874 -0.4064)
			(stroke
				(width 0.1524)
				(type default)
			)
			(layer "F.SilkS")
		)
		(fp_line
			(start 0.7874 -0.4064)
			(end 0.7874 0.4064)
			(stroke
				(width 0.1524)
				(type default)
			)
			(layer "F.SilkS")
		)
		(fp_line
			(start -0.67945 0.3048)
			(end -0.67945 -0.305054)
			(stroke
				(width 0.1)
				(type default)
			)
			(layer "F.Fab")
		)
		(fp_line
			(start -0.12065 0.3048)
			(end -0.67945 0.3048)
			(stroke
				(width 0.1)
				(type default)
			)
			(layer "F.Fab")
		)
		(fp_line
			(start 0.120396 0.3048)
			(end 0.120396 0.2794)
			(stroke
				(width 0.1)
				(type default)
			)
			(layer "F.Fab")
		)
		(fp_line
			(start 0.67945 0.3048)
			(end 0.120396 0.3048)
			(stroke
				(width 0.1)
				(type default)
			)
			(layer "F.Fab")
		)
		(fp_line
			(start -0.12065 0.2794)
			(end -0.12065 0.3048)
			(stroke
				(width 0.1)
				(type default)
			)
			(layer "F.Fab")
		)
		(fp_line
			(start 0.120396 0.2794)
			(end -0.12065 0.2794)
			(stroke
				(width 0.1)
				(type default)
			)
			(layer "F.Fab")
		)
		(fp_line
			(start -0.12065 -0.2794)
			(end 0.12065 -0.2794)
			(stroke
				(width 0.1)
				(type default)
			)
			(layer "F.Fab")
		)
		(fp_line
			(start 0.12065 -0.2794)
			(end 0.12065 -0.3048)
			(stroke
				(width 0.1)
				(type default)
			)
			(layer "F.Fab")
		)
		(fp_line
			(start 0.12065 -0.3048)
			(end 0.67945 -0.3048)
			(stroke
				(width 0.1)
				(type default)
			)
			(layer "F.Fab")
		)
		(fp_line
			(start 0.67945 -0.3048)
			(end 0.67945 0.3048)
			(stroke
				(width 0.1)
				(type default)
			)
			(layer "F.Fab")
		)
		(fp_line
			(start -0.67945 -0.305054)
			(end -0.12065 -0.305054)
			(stroke
				(width 0.1)
				(type default)
			)
			(layer "F.Fab")
		)
		(fp_line
			(start -0.12065 -0.305054)
			(end -0.12065 -0.2794)
			(stroke
				(width 0.1)
				(type default)
			)
			(layer "F.Fab")
		)
		(pad "1" smd circle
			(at -0.40005 0 270)
			(size 0 0)
			(layers "F.Cu" "F.Mask" "F.Paste")
			(net "SMB_BMC_ALERT16_N")
		)
		(pad "2" smd circle
			(at 0.40005 0 270)
			(size 0 0)
			(layers "F.Cu" "F.Mask" "F.Paste")
			(net "SMB_BMC_ALERT16_R2_N")
		)
	)
	(footprint ""
		(layer "F.Cu")
		(at 39.8272 -77.4954)
		(property "Reference" "R549"
			(at 0 0 0)
			(layer "F.SilkS")
			(hide yes)
			(effects
				(font
					(size 1.27 1.27)
				)
			)
		)
		(property "Value" ""
			(at 0 0 0)
			(layer "F.Fab")
			(effects
				(font
					(size 1.27 1.27)
				)
			)
		)
		(duplicate_pad_numbers_are_jumpers no)
		(fp_line
			(start -0.7874 -0.4064)
			(end 0.7874 -0.4064)
			(stroke
				(width 0.1524)
				(type default)
			)
			(layer "F.SilkS")
		)
		(fp_line
			(start -0.7874 0.4064)
			(end -0.7874 -0.4064)
			(stroke
				(width 0.1524)
				(type default)
			)
			(layer "F.SilkS")
		)
		(fp_line
			(start 0.7874 -0.4064)
			(end 0.7874 0.4064)
			(stroke
				(width 0.1524)
				(type default)
			)
			(layer "F.SilkS")
		)
		(fp_line
			(start 0.7874 0.4064)
			(end -0.7874 0.4064)
			(stroke
				(width 0.1524)
				(type default)
			)
			(layer "F.SilkS")
		)
		(fp_line
			(start -0.67945 -0.305054)
			(end -0.12065 -0.305054)
			(stroke
				(width 0.1)
				(type default)
			)
			(layer "F.Fab")
		)
		(fp_line
			(start -0.67945 0.3048)
			(end -0.67945 -0.305054)
			(stroke
				(width 0.1)
				(type default)
			)
			(layer "F.Fab")
		)
		(fp_line
			(start -0.12065 -0.305054)
			(end -0.12065 -0.2794)
			(stroke
				(width 0.1)
				(type default)
			)
			(layer "F.Fab")
		)
		(fp_line
			(start -0.12065 -0.2794)
			(end 0.12065 -0.2794)
			(stroke
				(width 0.1)
				(type default)
			)
			(layer "F.Fab")
		)
		(fp_line
			(start -0.12065 0.2794)
			(end -0.12065 0.3048)
			(stroke
				(width 0.1)
				(type default)
			)
			(layer "F.Fab")
		)
		(fp_line
			(start -0.12065 0.3048)
			(end -0.67945 0.3048)
			(stroke
				(width 0.1)
				(type default)
			)
			(layer "F.Fab")
		)
		(fp_line
			(start 0.120396 0.2794)
			(end -0.12065 0.2794)
			(stroke
				(width 0.1)
				(type default)
			)
			(layer "F.Fab")
		)
		(fp_line
			(start 0.120396 0.3048)
			(end 0.120396 0.2794)
			(stroke
				(width 0.1)
				(type default)
			)
			(layer "F.Fab")
		)
		(fp_line
			(start 0.12065 -0.3048)
			(end 0.67945 -0.3048)
			(stroke
				(width 0.1)
				(type default)
			)
			(layer "F.Fab")
		)
		(fp_line
			(start 0.12065 -0.2794)
			(end 0.12065 -0.3048)
			(stroke
				(width 0.1)
				(type default)
			)
			(layer "F.Fab")
		)
		(fp_line
			(start 0.67945 -0.3048)
			(end 0.67945 0.3048)
			(stroke
				(width 0.1)
				(type default)
			)
			(layer "F.Fab")
		)
		(fp_line
			(start 0.67945 0.3048)
			(end 0.120396 0.3048)
			(stroke
				(width 0.1)
				(type default)
			)
			(layer "F.Fab")
		)
		(pad "1" smd circle
			(at -0.40005 0)
			(size 0 0)
			(layers "F.Cu" "F.Mask" "F.Paste")
			(net "SPI_BMC_CLK_FLASH_R")
		)
		(pad "2" smd circle
			(at 0.40005 0)
			(size 0 0)
			(layers "F.Cu" "F.Mask" "F.Paste")
			(net "SPI_BMC_BOOT_CLK")
		)
	)
	(footprint ""
		(layer "F.Cu")
		(at 11.303 -17.399 -90)
		(property "Reference" "Q12"
			(at -0.714502 1.600708 90)
			(unlocked yes)
			(layer "F.SilkS")
			(effects
				(font
					(size 0.7874 0.5842)
					(thickness 0.1524)
				)
				(justify left)
			)
		)
		(property "Value" ""
			(at 0 0 270)
			(layer "F.Fab")
			(effects
				(font
					(size 1.27 1.27)
				)
			)
		)
		(duplicate_pad_numbers_are_jumpers no)
		(fp_line
			(start -1.332738 1.100074)
			(end -1.332738 -1.100074)
			(stroke
				(width 0.1524)
				(type default)
			)
			(layer "F.SilkS")
		)
		(fp_line
			(start 1.332738 1.100074)
			(end -1.332738 1.100074)
			(stroke
				(width 0.1524)
				(type default)
			)
			(layer "F.SilkS")
		)
		(fp_line
			(start 0 -0.541274)
			(end 0.4826 -1.100074)
			(stroke
				(width 0.1524)
				(type default)
			)
			(layer "F.SilkS")
		)
		(fp_line
			(start -1.332738 -1.100074)
			(end -0.4826 -1.100074)
			(stroke
				(width 0.1524)
				(type default)
			)
			(layer "F.SilkS")
		)
		(fp_line
			(start -0.4826 -1.100074)
			(end 0 -0.541274)
			(stroke
				(width 0.1524)
				(type default)
			)
			(layer "F.SilkS")
		)
		(fp_line
			(start 0.4826 -1.100074)
			(end 1.332738 -1.100074)
			(stroke
				(width 0.1524)
				(type default)
			)
			(layer "F.SilkS")
		)
		(fp_line
			(start 1.332738 -1.100074)
			(end 1.332738 1.100074)
			(stroke
				(width 0.1524)
				(type default)
			)
			(layer "F.SilkS")
		)
		(fp_poly
			(pts
				(xy -1.78181 0.260604) (xy -2.278126 -0.235712) (xy -1.533398 -0.484124)
			)
			(stroke
				(width 0)
				(type default)
			)
			(fill yes)
			(layer "F.SilkS")
		)
		(fp_line
			(start -0.674878 1.100074)
			(end -0.674878 -1.100074)
			(stroke
				(width 0.1)
				(type default)
			)
			(layer "F.Fab")
		)
		(fp_line
			(start 0.674878 1.100074)
			(end -0.674878 1.100074)
			(stroke
				(width 0.1)
				(type default)
			)
			(layer "F.Fab")
		)
		(fp_line
			(start -0.674878 -1.100074)
			(end 0.674878 -1.100074)
			(stroke
				(width 0.1)
				(type default)
			)
			(layer "F.Fab")
		)
		(fp_line
			(start 0.674878 -1.100074)
			(end 0.674878 1.100074)
			(stroke
				(width 0.1)
				(type default)
			)
			(layer "F.Fab")
		)
		(fp_poly
			(pts
				(xy -2.2352 -0.298958) (xy -2.2352 -1.001014) (xy -1.533144 -0.649986)
			)
			(stroke
				(width 0)
				(type default)
			)
			(fill yes)
			(layer "F.Fab")
		)
		(pad "1" smd rect
			(at -0.94996 -0.649986)
			(size 0.4318 0.508)
			(layers "F.Cu" "F.Mask" "F.Paste")
			(net "GND")
		)
		(pad "2" smd rect
			(at -0.94996 0)
			(size 0.4318 0.508)
			(layers "F.Cu" "F.Mask" "F.Paste")
			(net "PWR_LED")
		)
		(pad "3" smd rect
			(at -0.94996 0.649986)
			(size 0.4318 0.508)
			(layers "F.Cu" "F.Mask" "F.Paste")
			(net "HDD_LED_BUF")
		)
		(pad "4" smd rect
			(at 0.94996 0.649986)
			(size 0.4318 0.508)
			(layers "F.Cu" "F.Mask" "F.Paste")
			(net "GND")
		)
		(pad "5" smd rect
			(at 0.94996 0)
			(size 0.4318 0.508)
			(layers "F.Cu" "F.Mask" "F.Paste")
			(net "HDD_LED_N")
		)
		(pad "6" smd rect
			(at 0.94996 -0.649986)
			(size 0.4318 0.508)
			(layers "F.Cu" "F.Mask" "F.Paste")
			(net "PWR_LED_BUF_N")
		)
	)
	(footprint ""
		(layer "F.Cu")
		(at 73.72223 -10.922762 90)
		(property "Reference" "C181"
			(at 0 0 90)
			(layer "F.SilkS")
			(hide yes)
			(effects
				(font
					(size 1.27 1.27)
				)
			)
		)
		(property "Value" ""
			(at 0 0 90)
			(layer "F.Fab")
			(effects
				(font
					(size 1.27 1.27)
				)
			)
		)
		(duplicate_pad_numbers_are_jumpers no)
		(fp_line
			(start 0.7874 -0.4064)
			(end 0.7874 0.4064)
			(stroke
				(width 0.1524)
				(type default)
			)
			(layer "F.SilkS")
		)
		(fp_line
			(start -0.7874 -0.4064)
			(end 0.7874 -0.4064)
			(stroke
				(width 0.1524)
				(type default)
			)
			(layer "F.SilkS")
		)
		(fp_line
			(start 0.7874 0.4064)
			(end -0.7874 0.4064)
			(stroke
				(width 0.1524)
				(type default)
			)
			(layer "F.SilkS")
		)
		(fp_line
			(start -0.7874 0.4064)
			(end -0.7874 -0.4064)
			(stroke
				(width 0.1524)
				(type default)
			)
			(layer "F.SilkS")
		)
		(fp_line
			(start -0.12065 -0.305054)
			(end -0.12065 -0.2794)
			(stroke
				(width 0.1)
				(type default)
			)
			(layer "F.Fab")
		)
		(fp_line
			(start -0.67945 -0.305054)
			(end -0.12065 -0.305054)
			(stroke
				(width 0.1)
				(type default)
			)
			(layer "F.Fab")
		)
		(fp_line
			(start 0.67945 -0.3048)
			(end 0.67945 0.3048)
			(stroke
				(width 0.1)
				(type default)
			)
			(layer "F.Fab")
		)
		(fp_line
			(start 0.12065 -0.3048)
			(end 0.67945 -0.3048)
			(stroke
				(width 0.1)
				(type default)
			)
			(layer "F.Fab")
		)
		(fp_line
			(start 0.12065 -0.2794)
			(end 0.12065 -0.3048)
			(stroke
				(width 0.1)
				(type default)
			)
			(layer "F.Fab")
		)
		(fp_line
			(start -0.12065 -0.2794)
			(end 0.12065 -0.2794)
			(stroke
				(width 0.1)
				(type default)
			)
			(layer "F.Fab")
		)
		(fp_line
			(start 0.120396 0.2794)
			(end -0.12065 0.2794)
			(stroke
				(width 0.1)
				(type default)
			)
			(layer "F.Fab")
		)
		(fp_line
			(start -0.12065 0.2794)
			(end -0.12065 0.3048)
			(stroke
				(width 0.1)
				(type default)
			)
			(layer "F.Fab")
		)
		(fp_line
			(start 0.67945 0.3048)
			(end 0.120396 0.3048)
			(stroke
				(width 0.1)
				(type default)
			)
			(layer "F.Fab")
		)
		(fp_line
			(start 0.120396 0.3048)
			(end 0.120396 0.2794)
			(stroke
				(width 0.1)
				(type default)
			)
			(layer "F.Fab")
		)
		(fp_line
			(start -0.12065 0.3048)
			(end -0.67945 0.3048)
			(stroke
				(width 0.1)
				(type default)
			)
			(layer "F.Fab")
		)
		(fp_line
			(start -0.67945 0.3048)
			(end -0.67945 -0.305054)
			(stroke
				(width 0.1)
				(type default)
			)
			(layer "F.Fab")
		)
		(pad "1" smd circle
			(at -0.40005 0 90)
			(size 0 0)
			(layers "F.Cu" "F.Mask" "F.Paste")
			(net "REAR_AC_PWR_BTN")
		)
		(pad "2" smd circle
			(at 0.40005 0 90)
			(size 0 0)
			(layers "F.Cu" "F.Mask" "F.Paste")
			(net "GND")
		)
	)
)
